# T6G (Grand Teton) — schematic netlist excerpt (pin names and nets, part order shuffled) for the footprints in the layout excerpt that follows; sources: Cadence DE-HDL packaged netlist, KiCad conversion of 04192023_DAF0TMB3IC0_F0TG_MB_C_brd_V02_OCP.brd

PR485  Q_RES  1.5 1% EMPTY  pkg 0402LF  page 211 : A = SW_PVDDCR_CPU0_P1_SW1_RC ; B = GND

(kicad_pcb
	(version 20260206)
	(generator "pcbnew")
	(generator_version "10.0")
	(general
		(thickness 1.6)
		(legacy_teardrops no)
	)
	(paper "A4")
	(title_block
		(title "04192023_DAF0TMB3IC0_F0TG_MB_C_brd_V02_OCP.brd")
		(comment 1 "Grand Teton / footprints 988-988 of 8354")
	)
	(layers
		(0 "F.Cu" signal "TOP")
		(4 "In1.Cu" signal "GND")
		(6 "In2.Cu" signal "IN1")
		(8 "In3.Cu" signal "GND1")
		(10 "In4.Cu" signal "IN2")
		(12 "In5.Cu" signal "GND2")
		(14 "In6.Cu" signal "IN3")
		(16 "In7.Cu" signal "GND3")
		(18 "In8.Cu" signal "VCC")
		(20 "In9.Cu" signal "VCC1")
		(22 "In10.Cu" signal "GND4")
		(24 "In11.Cu" signal "IN4")
		(26 "In12.Cu" signal "GND5")
		(28 "In13.Cu" signal "IN5")
		(30 "In14.Cu" signal "GND6")
		(32 "In15.Cu" signal "IN6")
		(34 "In16.Cu" signal "GND7")
		(2 "B.Cu" signal "BOTTOM")
		(9 "F.Adhes" user "F.Adhesive")
		(11 "B.Adhes" user "B.Adhesive")
		(13 "F.Paste" user "Package Geometry/Pastemask Top")
		(15 "B.Paste" user "Package Geometry/Pastemask Bottom")
		(5 "F.SilkS" user "Ref Des/Silkscreen Top")
		(7 "B.SilkS" user "Ref Des/Silkscreen Bottom")
		(1 "F.Mask" user "Board Geometry/Soldermask Top")
		(3 "B.Mask" user "Board Geometry/Soldermask Bottom")
		(17 "Dwgs.User" user "User.Drawings")
		(19 "Cmts.User" user "User.Comments")
		(21 "Eco1.User" user "User.Eco1")
		(23 "Eco2.User" user "User.Eco2")
		(25 "Edge.Cuts" user "Board Geometry/Outline")
		(27 "Margin" user)
		(31 "F.CrtYd" user "Package Geometry/Place Bound Top")
		(29 "B.CrtYd" user "Package Geometry/Place Bound Bottom")
		(35 "F.Fab" user "Ref Des/Assembly Top")
		(33 "B.Fab" user "Ref Des/Assembly Bottom")
	)
	(footprint ""
		(layer "F.Cu")
		(at 85.961728 -184.478168 -90)
		(property "Reference" "PR485"
			(at 0 0 270)
			(layer "F.SilkS")
			(hide yes)
			(effects
				(font
					(size 1.27 1.27)
				)
			)
		)
		(property "Value" ""
			(at 0 0 270)
			(layer "F.Fab")
			(effects
				(font
					(size 1.27 1.27)
				)
			)
		)
		(duplicate_pad_numbers_are_jumpers no)
		(fp_line
			(start -0.7874 0.4064)
			(end -0.7874 -0.4064)
			(stroke
				(width 0.1524)
				(type default)
			)
			(layer "F.SilkS")
		)
		(fp_line
			(start 0.7874 0.4064)
			(end -0.7874 0.4064)
			(stroke
				(width 0.1524)
				(type default)
			)
			(layer "F.SilkS")
		)
		(fp_line
			(start -0.7874 -0.4064)
			(end 0.7874 -0.4064)
			(stroke
				(width 0.1524)
				(type default)
			)
			(layer "F.SilkS")
		)
		(fp_line
			(start 0.7874 -0.4064)
			(end 0.7874 0.4064)
			(stroke
				(width 0.1524)
				(type default)
			)
			(layer "F.SilkS")
		)
		(fp_line
			(start -0.67945 0.3048)
			(end -0.67945 -0.305054)
			(stroke
				(width 0.1)
				(type default)
			)
			(layer "F.Fab")
		)
		(fp_line
			(start -0.12065 0.3048)
			(end -0.67945 0.3048)
			(stroke
				(width 0.1)
				(type default)
			)
			(layer "F.Fab")
		)
		(fp_line
			(start 0.120396 0.3048)
			(end 0.120396 0.2794)
			(stroke
				(width 0.1)
				(type default)
			)
			(layer "F.Fab")
		)
		(fp_line
			(start 0.67945 0.3048)
			(end 0.120396 0.3048)
			(stroke
				(width 0.1)
				(type default)
			)
			(layer "F.Fab")
		)
		(fp_line
			(start -0.12065 0.2794)
			(end -0.12065 0.3048)
			(stroke
				(width 0.1)
				(type default)
			)
			(layer "F.Fab")
		)
		(fp_line
			(start 0.120396 0.2794)
			(end -0.12065 0.2794)
			(stroke
				(width 0.1)
				(type default)
			)
			(layer "F.Fab")
		)
		(fp_line
			(start -0.12065 -0.2794)
			(end 0.12065 -0.2794)
			(stroke
				(width 0.1)
				(type default)
			)
			(layer "F.Fab")
		)
		(fp_line
			(start 0.12065 -0.2794)
			(end 0.12065 -0.3048)
			(stroke
				(width 0.1)
				(type default)
			)
			(layer "F.Fab")
		)
		(fp_line
			(start 0.12065 -0.3048)
			(end 0.67945 -0.3048)
			(stroke
				(width 0.1)
				(type default)
			)
			(layer "F.Fab")
		)
		(fp_line
			(start 0.67945 -0.3048)
			(end 0.67945 0.3048)
			(stroke
				(width 0.1)
				(type default)
			)
			(layer "F.Fab")
		)
		(fp_line
			(start -0.67945 -0.305054)
			(end -0.12065 -0.305054)
			(stroke
				(width 0.1)
				(type default)
			)
			(layer "F.Fab")
		)
		(fp_line
			(start -0.12065 -0.305054)
			(end -0.12065 -0.2794)
			(stroke
				(width 0.1)
				(type default)
			)
			(layer "F.Fab")
		)
		(pad "1" smd circle
			(at -0.40005 0 270)
			(size 0 0)
			(layers "F.Cu" "F.Mask" "F.Paste")
			(net "SW_PVDDCR_CPU0_P1_SW1_RC")
		)
		(pad "2" smd circle
			(at 0.40005 0 270)
			(size 0 0)
			(layers "F.Cu" "F.Mask" "F.Paste")
			(net "GND")
		)
	)
)
